(kicad_pcb
	(version 20260206)
	(generator "pcbnew")
	(generator_version "10.0")
	(general
		(thickness 1.6)
		(legacy_teardrops no)
	)
	(paper "A4")
	(title_block
		(title "Bryce Canyon_F.DPB_16315-1-OCP.brd")
		(comment 1 "Bryce Canyon / footprints 102-105 of 2223")
	)
	(layers
		(0 "F.Cu" signal "TOP")
		(4 "In1.Cu" signal "L2GND")
		(6 "In2.Cu" signal "L3")
		(8 "In3.Cu" signal "L4GND")
		(10 "In4.Cu" signal "L5")
		(12 "In5.Cu" signal "L6VCC")
		(14 "In6.Cu" signal "L7VCC")
		(16 "In7.Cu" signal "L8")
		(18 "In8.Cu" signal "L9GND")
		(20 "In9.Cu" signal "L10")
		(22 "In10.Cu" signal "L11GND")
		(2 "B.Cu" signal "BOTTOM")
		(9 "F.Adhes" user "F.Adhesive")
		(11 "B.Adhes" user "B.Adhesive")
		(13 "F.Paste" user "Package Geometry/Pastemask Top")
		(15 "B.Paste" user "Package Geometry/Pastemask Bottom")
		(5 "F.SilkS" user "Ref Des/Silkscreen Top")
		(7 "B.SilkS" user "Ref Des/Silkscreen Bottom")
		(1 "F.Mask" user "Board Geometry/Soldermask Top")
		(3 "B.Mask" user "Board Geometry/Soldermask Bottom")
		(17 "Dwgs.User" user "User.Drawings")
		(19 "Cmts.User" user "User.Comments")
		(21 "Eco1.User" user "User.Eco1")
		(23 "Eco2.User" user "User.Eco2")
		(25 "Edge.Cuts" user "Board Geometry/Outline")
		(27 "Margin" user)
		(31 "F.CrtYd" user "Package Geometry/Place Bound Top")
		(29 "B.CrtYd" user "Package Geometry/Place Bound Bottom")
		(35 "F.Fab" user "Ref Des/Assembly Top")
		(33 "B.Fab" user "Ref Des/Assembly Bottom")
	)
	(footprint ""
		(layer "F.Cu")
		(at 185.950098 -57.909968 -90)
		(property "Reference" "HDDSAS29"
			(at 0 0 270)
			(layer "F.SilkS")
			(hide yes)
			(effects
				(font
					(size 1.27 1.27)
				)
			)
		)
		(property "Value" "SKT-SAS15P-14P-45-GP"
			(at -20.7645 -8.9789 270)
			(unlocked yes)
			(layer "F.Fab")
			(hide yes)
			(effects
				(font
					(size 1.016 1.016)
					(thickness 0.1524)
				)
			)
		)
		(property "Device Type" "10120818-001C-TRLF"
			(at -20.7645 -10.5029 270)
			(unlocked yes)
			(layer "F.Fab")
			(hide yes)
			(effects
				(font
					(size 1.016 1.016)
					(thickness 0.1524)
				)
			)
		)
		(duplicate_pad_numbers_are_jumpers no)
		(fp_line
			(start 1.651 4.2926)
			(end 1.651 3.0099)
			(stroke
				(width 0.1524)
				(type default)
			)
			(layer "F.SilkS")
		)
		(fp_line
			(start 8.509 4.2926)
			(end 1.651 4.2926)
			(stroke
				(width 0.1524)
				(type default)
			)
			(layer "F.SilkS")
		)
		(fp_line
			(start -23.4188 3.0099)
			(end -23.4188 -3.2512)
			(stroke
				(width 0.1524)
				(type default)
			)
			(layer "F.SilkS")
		)
		(fp_line
			(start 1.651 3.0099)
			(end -23.4188 3.0099)
			(stroke
				(width 0.1524)
				(type default)
			)
			(layer "F.SilkS")
		)
		(fp_line
			(start 8.509 3.0099)
			(end 8.509 4.2926)
			(stroke
				(width 0.1524)
				(type default)
			)
			(layer "F.SilkS")
		)
		(fp_line
			(start 23.4188 3.0099)
			(end 8.509 3.0099)
			(stroke
				(width 0.1524)
				(type default)
			)
			(layer "F.SilkS")
		)
		(fp_line
			(start -23.4188 -3.2512)
			(end 23.4188 -3.2512)
			(stroke
				(width 0.1524)
				(type default)
			)
			(layer "F.SilkS")
		)
		(fp_line
			(start 23.4188 -3.2512)
			(end 23.4188 3.0099)
			(stroke
				(width 0.1524)
				(type default)
			)
			(layer "F.SilkS")
		)
		(fp_line
			(start 15.5067 -3.3401)
			(end 16.2687 -3.3401)
			(stroke
				(width 0.3302)
				(type default)
			)
			(layer "F.SilkS")
		)
		(fp_poly
			(pts
				(xy 15.868904 -3.230372) (xy 16.503904 -3.865372) (xy 15.233904 -3.865372)
			)
			(stroke
				(width 0)
				(type default)
			)
			(fill yes)
			(layer "F.SilkS")
		)
		(fp_poly
			(pts
				(xy -22.8727 -2.7559) (xy 22.8727 -2.7559) (xy 22.8727 2.7559) (xy 8.255 2.7559) (xy 8.255 3.5179)
				(xy 1.905 3.5179) (xy 1.905 2.7559) (xy -22.8727 2.7559)
			)
			(stroke
				(width 0)
				(type default)
			)
			(fill no)
			(layer "F.CrtYd")
		)
		(fp_poly
			(pts
				(xy 1.397 4.5466) (xy 1.397 3.2639) (xy -23.6728 3.2639) (xy -23.6728 -3.5052) (xy 23.6728 -3.5052)
				(xy 23.6728 -0.00635) (xy 22.8727 -0.00635) (xy 22.8727 -2.7559) (xy -22.8727 -2.7559) (xy -22.8727 2.7559)
				(xy 1.905 2.7559) (xy 1.905 3.5179) (xy 8.255 3.5179) (xy 8.255 2.7559) (xy 22.8727 2.7559) (xy 22.8727 0.00635)
				(xy 23.6728 0.00635) (xy 23.6728 3.2639) (xy 8.763 3.2639) (xy 8.763 4.5466)
			)
			(stroke
				(width 0)
				(type default)
			)
			(fill no)
			(layer "F.CrtYd")
		)
		(fp_poly
			(pts
				(xy 1.397 4.5466) (xy 1.397 3.2639) (xy -23.6728 3.2639) (xy -23.6728 -3.5052) (xy 23.6728 -3.5052)
				(xy 23.6728 3.2639) (xy 8.763 3.2639) (xy 8.763 4.5466)
			)
			(stroke
				(width 0)
				(type default)
			)
			(fill no)
			(layer "F.Fab")
		)
		(pad "" np_thru_hole circle
			(at -18.874994 0 270)
			(size 0.254 0.254)
			(drill 1.3462)
			(layers "*.Cu" "*.Mask")
			(clearance 0.9017)
			(thermal_gap 0.9017)
		)
		(pad "" np_thru_hole circle
			(at 18.874994 0 270)
			(size 0.254 0.254)
			(drill 0.9398)
			(layers "*.Cu" "*.Mask")
			(clearance 0.6985)
			(thermal_gap 0.6985)
		)
		(pad "G1" smd rect
			(at 21.874988 0 270)
			(size 2.5908 2.5908)
			(layers "F.Cu" "F.Mask" "F.Paste")
			(net "GND")
		)
		(pad "G2" smd rect
			(at -21.874988 0 270)
			(size 2.5908 2.5908)
			(layers "F.Cu" "F.Mask" "F.Paste")
			(net "GND")
		)
		(pad "P1" smd rect
			(at 1.905 -1.82499 270)
			(size 0.6096 2.3622)
			(layers "F.Cu" "F.Mask" "F.Paste")
			(net "Net_2061")
		)
		(pad "P2" smd rect
			(at 0.635 -1.82499 270)
			(size 0.6096 2.3622)
			(layers "F.Cu" "F.Mask" "F.Paste")
			(net "Net_2062")
		)
		(pad "P3" smd rect
			(at -0.635 -1.82499 270)
			(size 0.6096 2.3622)
			(layers "F.Cu" "F.Mask" "F.Paste")
			(net "Net_2063")
		)
		(pad "P4" smd rect
			(at -1.905 -1.82499 270)
			(size 0.6096 2.3622)
			(layers "F.Cu" "F.Mask" "F.Paste")
			(net "GND")
		)
		(pad "P5" smd rect
			(at -3.175 -1.82499 270)
			(size 0.6096 2.3622)
			(layers "F.Cu" "F.Mask" "F.Paste")
			(net "HDD_PRSNT_29")
		)
		(pad "P6" smd rect
			(at -4.445 -1.82499 270)
			(size 0.6096 2.3622)
			(layers "F.Cu" "F.Mask" "F.Paste")
			(net "GND")
		)
		(pad "P7" smd rect
			(at -5.715 -1.82499 270)
			(size 0.6096 2.3622)
			(layers "F.Cu" "F.Mask" "F.Paste")
			(net "5V_PRE_29")
		)
		(pad "P8" smd rect
			(at -6.985 -1.82499 270)
			(size 0.6096 2.3622)
			(layers "F.Cu" "F.Mask" "F.Paste")
			(net "P5V_HDD29")
		)
		(pad "P9" smd rect
			(at -8.255 -1.82499 270)
			(size 0.6096 2.3622)
			(layers "F.Cu" "F.Mask" "F.Paste")
			(net "P5V_HDD29")
		)
		(pad "P10" smd rect
			(at -9.525 -1.82499 270)
			(size 0.6096 2.3622)
			(layers "F.Cu" "F.Mask" "F.Paste")
			(net "GND")
		)
		(pad "P11" smd rect
			(at -10.795 -1.82499 270)
			(size 0.6096 2.3622)
			(layers "F.Cu" "F.Mask" "F.Paste")
			(net "ACT_HDD_29")
		)
		(pad "P12" smd rect
			(at -12.065 -1.82499 270)
			(size 0.6096 2.3622)
			(layers "F.Cu" "F.Mask" "F.Paste")
			(net "GND")
		)
		(pad "P13" smd rect
			(at -13.335 -1.82499 270)
			(size 0.6096 2.3622)
			(layers "F.Cu" "F.Mask" "F.Paste")
			(net "12V_PRE_29")
		)
		(pad "P14" smd rect
			(at -14.605 -1.82499 270)
			(size 0.6096 2.3622)
			(layers "F.Cu" "F.Mask" "F.Paste")
			(net "P12V_HDD29")
		)
		(pad "P15" smd rect
			(at -15.875 -1.82499 270)
			(size 0.6096 2.3622)
			(layers "F.Cu" "F.Mask" "F.Paste")
			(net "P12V_HDD29")
		)
		(pad "S1" smd rect
			(at 15.875 -1.82499 270)
			(size 0.6096 2.3622)
			(layers "F.Cu" "F.Mask" "F.Paste")
			(net "GND")
		)
		(pad "S2" smd rect
			(at 14.605 -1.82499 270)
			(size 0.6096 2.3622)
			(layers "F.Cu" "F.Mask" "F.Paste")
			(net "SAS_HDD_RX_P29")
		)
		(pad "S3" smd rect
			(at 13.335 -1.82499 270)
			(size 0.6096 2.3622)
			(layers "F.Cu" "F.Mask" "F.Paste")
			(net "SAS_HDD_RX_N29")
		)
		(pad "S4" smd rect
			(at 12.065 -1.82499 270)
			(size 0.6096 2.3622)
			(layers "F.Cu" "F.Mask" "F.Paste")
			(net "GND")
		)
		(pad "S5" smd rect
			(at 10.795 -1.82499 270)
			(size 0.6096 2.3622)
			(layers "F.Cu" "F.Mask" "F.Paste")
			(net "PHY_DRV_A_TO_SCC_A_29_DN")
		)
		(pad "S6" smd rect
			(at 9.525 -1.82499 270)
			(size 0.6096 2.3622)
			(layers "F.Cu" "F.Mask" "F.Paste")
			(net "PHY_DRV_A_TO_SCC_A_29_DP")
		)
		(pad "S7" smd rect
			(at 8.255 -1.82499 270)
			(size 0.6096 2.3622)
			(layers "F.Cu" "F.Mask" "F.Paste")
			(net "GND")
		)
		(pad "S8" smd rect
			(at 7.480046 2.845054 270)
			(size 0.508 2.3622)
			(layers "F.Cu" "F.Mask" "F.Paste")
			(net "GND")
		)
		(pad "S9" smd rect
			(at 6.679946 2.845054 270)
			(size 0.508 2.3622)
			(layers "F.Cu" "F.Mask" "F.Paste")
			(net "Net_468")
		)
		(pad "S10" smd rect
			(at 5.8801 2.845054 270)
			(size 0.508 2.3622)
			(layers "F.Cu" "F.Mask" "F.Paste")
			(net "Net_360")
		)
		(pad "S11" smd rect
			(at 5.08 2.845054 270)
			(size 0.508 2.3622)
			(layers "F.Cu" "F.Mask" "F.Paste")
			(net "GND")
		)
		(pad "S12" smd rect
			(at 4.2799 2.845054 270)
			(size 0.508 2.3622)
			(layers "F.Cu" "F.Mask" "F.Paste")
			(net "Net_396")
		)
		(pad "S13" smd rect
			(at 3.480054 2.845054 270)
			(size 0.508 2.3622)
			(layers "F.Cu" "F.Mask" "F.Paste")
			(net "Net_432")
		)
		(pad "S14" smd rect
			(at 2.679954 2.845054 270)
			(size 0.508 2.3622)
			(layers "F.Cu" "F.Mask" "F.Paste")
			(net "GND")
		)
		(zone
			(layer "F.Cu")
			(hatch none 0.5)
			(connect_pads
				(clearance 0)
			)
			(min_thickness 0.25)
			(keepout
				(tracks not_allowed)
				(vias allowed)
				(pads allowed)
				(copperpour not_allowed)
				(footprints allowed)
			)
			(placement
				(enabled no)
				(sheetname "")
			)
			(fill
				(thermal_gap 0.5)
				(thermal_bridge_width 0.5)
				(island_removal_mode 0)
			)
			(polygon
				(pts
					(xy 189.607698 -74.648568) (xy 182.533798 -74.648568) (xy 182.533798 -81.582768) (xy 183.638698 -81.582768)
					(xy 183.638698 -77.467968) (xy 188.261498 -77.467968) (xy 188.261498 -81.582768) (xy 189.607698 -81.582768)
				)
			)
		)
		(zone
			(layer "F.Cu")
			(hatch none 0.5)
			(connect_pads
				(clearance 0)
			)
			(min_thickness 0.25)
			(keepout
				(tracks allowed)
				(vias not_allowed)
				(pads allowed)
				(copperpour not_allowed)
				(footprints allowed)
			)
			(placement
				(enabled no)
				(sheetname "")
			)
			(fill
				(thermal_gap 0.5)
				(thermal_bridge_width 0.5)
				(island_removal_mode 0)
			)
			(polygon
				(pts
					(xy 189.607698 -74.648568) (xy 182.533798 -74.648568) (xy 182.533798 -81.582768) (xy 183.638698 -81.582768)
					(xy 183.638698 -77.467968) (xy 188.261498 -77.467968) (xy 188.261498 -81.582768) (xy 189.607698 -81.582768)
				)
			)
		)
		(zone
			(layer "F.Cu")
			(hatch none 0.5)
			(connect_pads
				(clearance 0)
			)
			(min_thickness 0.25)
			(keepout
				(tracks allowed)
				(vias not_allowed)
				(pads allowed)
				(copperpour not_allowed)
				(footprints allowed)
			)
			(placement
				(enabled no)
				(sheetname "")
			)
			(fill
				(thermal_gap 0.5)
				(thermal_bridge_width 0.5)
				(island_removal_mode 0)
			)
			(polygon
				(pts
					(xy 189.607698 -41.171368) (xy 182.533798 -41.171368) (xy 182.533798 -34.237168) (xy 183.638698 -34.237168)
					(xy 183.638698 -38.351968) (xy 188.261498 -38.351968) (xy 188.261498 -34.237168) (xy 189.607698 -34.237168)
				)
			)
		)
		(zone
			(layer "F.Cu")
			(hatch none 0.5)
			(connect_pads
				(clearance 0)
			)
			(min_thickness 0.25)
			(keepout
				(tracks not_allowed)
				(vias allowed)
				(pads allowed)
				(copperpour not_allowed)
				(footprints allowed)
			)
			(placement
				(enabled no)
				(sheetname "")
			)
			(fill
				(thermal_gap 0.5)
				(thermal_bridge_width 0.5)
				(island_removal_mode 0)
			)
			(polygon
				(pts
					(xy 189.607698 -41.171368) (xy 182.533798 -41.171368) (xy 182.533798 -34.237168) (xy 183.638698 -34.237168)
					(xy 183.638698 -38.351968) (xy 188.261498 -38.351968) (xy 188.261498 -34.237168) (xy 189.607698 -34.237168)
				)
			)
		)
		(zone
			(layers "F.Cu" "B.Cu" "In1.Cu" "In2.Cu" "In3.Cu" "In4.Cu" "In5.Cu" "In6.Cu"
				"In7.Cu" "In8.Cu" "In9.Cu" "In10.Cu"
			)
			(hatch none 0.5)
			(connect_pads
				(clearance 0)
			)
			(min_thickness 0.25)
			(keepout
				(tracks not_allowed)
				(vias allowed)
				(pads allowed)
				(copperpour not_allowed)
				(footprints allowed)
			)
			(placement
				(enabled no)
				(sheetname "")
			)
			(fill
				(thermal_gap 0.5)
				(thermal_bridge_width 0.5)
				(island_removal_mode 0)
			)
			(polygon
				(pts
					(arc
						(start 186.724798 -39.034974)
						(mid 185.175398 -39.034974)
						(end 186.724798 -39.034974)
					)
				)
			)
		)
		(zone
			(layers "F.Cu" "B.Cu" "In1.Cu" "In2.Cu" "In3.Cu" "In4.Cu" "In5.Cu" "In6.Cu"
				"In7.Cu" "In8.Cu" "In9.Cu" "In10.Cu"
			)
			(hatch none 0.5)
			(connect_pads
				(clearance 0)
			)
			(min_thickness 0.25)
			(keepout
				(tracks not_allowed)
				(vias allowed)
				(pads allowed)
				(copperpour not_allowed)
				(footprints allowed)
			)
			(placement
				(enabled no)
				(sheetname "")
			)
			(fill
				(thermal_gap 0.5)
				(thermal_bridge_width 0.5)
				(island_removal_mode 0)
			)
			(polygon
				(pts
					(arc
						(start 186.927998 -76.784962)
						(mid 184.972198 -76.784962)
						(end 186.927998 -76.784962)
					)
				)
			)
		)
	)
	(footprint ""
		(layer "F.Cu")
		(at 267.0048 -144.3482 90)
		(property "Reference" "TP202"
			(at 0 0 90)
			(layer "F.SilkS")
			(hide yes)
			(effects
				(font
					(size 1.27 1.27)
				)
			)
		)
		(property "Value" "TPAD32-GP"
			(at -0.0508 -1.6764 90)
			(unlocked yes)
			(layer "F.Fab")
			(hide yes)
			(effects
				(font
					(size 1.016 1.016)
					(thickness 0.1524)
				)
			)
		)
		(property "Device Type" "TPAD32"
			(at -0.0508 -3.2004 90)
			(unlocked yes)
			(layer "F.Fab")
			(hide yes)
			(effects
				(font
					(size 1.016 1.016)
					(thickness 0.1524)
				)
			)
		)
		(duplicate_pad_numbers_are_jumpers no)
		(fp_poly
			(pts
				(arc
					(start 0 0.4064)
					(mid 0 -0.4064)
					(end 0 0.4064)
				)
			)
			(stroke
				(width 0)
				(type default)
			)
			(fill no)
			(layer "F.CrtYd")
		)
		(fp_poly
			(pts
				(arc
					(start 0 0.7112)
					(mid 0 -0.7112)
					(end 0 0.7112)
				)
			)
			(stroke
				(width 0)
				(type default)
			)
			(fill no)
			(layer "F.Fab")
		)
		(pad "1" smd circle
			(at 0 0 90)
			(size 0.8128 0.8128)
			(layers "F.Cu" "F.Mask" "F.Paste")
			(net "TP_SMB_COMP_B_NIC_SCL")
		)
	)
	(footprint ""
		(layer "F.Cu")
		(at 280.834338 -234.928918)
		(property "Reference" "TC14"
			(at 0 0 0)
			(layer "F.SilkS")
			(hide yes)
			(effects
				(font
					(size 1.27 1.27)
				)
			)
		)
		(property "Value" "SE270U16VM-8-GP"
			(at -4.5974 -2.54 0)
			(unlocked yes)
			(layer "F.Fab")
			(hide yes)
			(effects
				(font
					(size 1.016 1.016)
					(thickness 0.1524)
				)
			)
		)
		(property "Device Type" "SE361416H394"
			(at -4.5974 -4.064 0)
			(unlocked yes)
			(layer "F.Fab")
			(hide yes)
			(effects
				(font
					(size 1.016 1.016)
					(thickness 0.1524)
				)
			)
		)
		(duplicate_pad_numbers_are_jumpers no)
		(fp_line
			(start -3.556 -3.4163)
			(end -2.3622 -4.6101)
			(stroke
				(width 0.1524)
				(type default)
			)
			(layer "F.SilkS")
		)
		(fp_line
			(start -3.556 4.6101)
			(end -3.556 -3.4163)
			(stroke
				(width 0.1524)
				(type default)
			)
			(layer "F.SilkS")
		)
		(fp_line
			(start -2.3622 -4.6101)
			(end 2.3622 -4.6101)
			(stroke
				(width 0.1524)
				(type default)
			)
			(layer "F.SilkS")
		)
		(fp_line
			(start 2.3622 -4.6101)
			(end 3.556 -3.4163)
			(stroke
				(width 0.1524)
				(type default)
			)
			(layer "F.SilkS")
		)
		(fp_line
			(start 3.556 -3.4163)
			(end 3.556 4.6101)
			(stroke
				(width 0.1524)
				(type default)
			)
			(layer "F.SilkS")
		)
		(fp_line
			(start 3.556 4.6101)
			(end -3.556 4.6101)
			(stroke
				(width 0.1524)
				(type default)
			)
			(layer "F.SilkS")
		)
		(fp_rect
			(start -3.302 3.6449)
			(end 3.302 -3.6449)
			(stroke
				(width 0)
				(type default)
			)
			(fill no)
			(layer "F.CrtYd")
		)
		(fp_poly
			(pts
				(xy 3.81 4.6863) (xy 3.81 -3.4925) (xy 3.302 -3.4925) (xy 3.302 3.6449) (xy -3.302 3.6449) (xy -3.302 -3.6449)
				(xy 3.302 -3.6449) (xy 3.302 -3.5052) (xy 3.81 -3.5052) (xy 3.81 -4.6863) (xy -3.81 -4.6863) (xy -3.81 4.6863)
			)
			(stroke
				(width 0)
				(type default)
			)
			(fill no)
			(layer "F.CrtYd")
		)
		(fp_rect
			(start -3.81 4.6863)
			(end 3.81 -4.6863)
			(stroke
				(width 0)
				(type default)
			)
			(fill no)
			(layer "F.Fab")
		)
		(pad "1" smd rect
			(at 0 -2.574036)
			(size 1.4224 3.556)
			(layers "F.Cu" "F.Mask" "F.Paste")
			(net "P12V_A")
		)
		(pad "2" smd rect
			(at 0 2.574036)
			(size 1.4224 3.556)
			(layers "F.Cu" "F.Mask" "F.Paste")
			(net "GND")
		)
	)
	(footprint ""
		(layer "F.Cu")
		(at 318.06515 -245.365016 -90)
		(property "Reference" "R478"
			(at 0 0 270)
			(layer "F.SilkS")
			(hide yes)
			(effects
				(font
					(size 1.27 1.27)
				)
			)
		)
		(property "Value" "4K7R2J-2-GP"
			(at 0.064008 -3.993896 270)
			(unlocked yes)
			(layer "F.Fab")
			(hide yes)
			(effects
				(font
					(size 1.016 1.016)
					(thickness 0.1524)
				)
			)
		)
		(property "Device Type" "R402H16"
			(at 0.064008 -5.517896 270)
			(unlocked yes)
			(layer "F.Fab")
			(hide yes)
			(effects
				(font
					(size 1.016 1.016)
					(thickness 0.1524)
				)
			)
		)
		(duplicate_pad_numbers_are_jumpers no)
		(fp_line
			(start -0.508 -0.9398)
			(end -0.508 0.9398)
			(stroke
				(width 0.1524)
				(type default)
			)
			(layer "F.SilkS")
		)
		(fp_line
			(start 0.508 -0.9398)
			(end -0.508 -0.9398)
			(stroke
				(width 0.1524)
				(type default)
			)
			(layer "F.SilkS")
		)
		(fp_rect
			(start -0.508 0.9398)
			(end 0.508 -0.9398)
			(stroke
				(width 0)
				(type default)
			)
			(fill no)
			(layer "F.CrtYd")
		)
		(fp_rect
			(start -0.508 0.9398)
			(end 0.508 -0.9398)
			(stroke
				(width 0)
				(type default)
			)
			(fill no)
			(layer "F.Fab")
		)
		(pad "1" smd custom
			(at 0 -0.4445 270)
			(size 0.1397 0.1397)
			(layers "F.Cu" "F.Mask" "F.Paste")
			(net "DRIVE_A_6_FLT_LED")
			(options
				(clearance outline)
				(anchor circle)
			)
			(primitives
				(gr_poly
					(pts
						(arc
							(start -0.1778 -0.2794)
							(mid -0.249642 -0.249642)
							(end -0.2794 -0.1778)
						)
						(arc
							(start -0.2794 0.1778)
							(mid -0.249642 0.249642)
							(end -0.1778 0.2794)
						)
						(arc
							(start 0.1778 0.2794)
							(mid 0.249642 0.249642)
							(end 0.2794 0.1778)
						)
						(arc
							(start 0.2794 -0.1778)
							(mid 0.249642 -0.249642)
							(end 0.1778 -0.2794)
						)
					)
					(width 0)
					(fill yes)
				)
			)
		)
		(pad "2" smd custom
			(at 0 0.4445 270)
			(size 0.1397 0.1397)
			(layers "F.Cu" "F.Mask" "F.Paste")
			(net "GND")
			(options
				(clearance outline)
				(anchor circle)
			)
			(primitives
				(gr_poly
					(pts
						(arc
							(start -0.1778 -0.2794)
							(mid -0.249642 -0.249642)
							(end -0.2794 -0.1778)
						)
						(arc
							(start -0.2794 0.1778)
							(mid -0.249642 0.249642)
							(end -0.1778 0.2794)
						)
						(arc
							(start 0.1778 0.2794)
							(mid 0.249642 0.249642)
							(end 0.2794 0.1778)
						)
						(arc
							(start 0.2794 -0.1778)
							(mid 0.249642 -0.249642)
							(end 0.1778 -0.2794)
						)
					)
					(width 0)
					(fill yes)
				)
			)
		)
	)
)
